(kicad_pcb
	(version 20260206)
	(generator "pcbnew")
	(generator_version "10.0")
	(general
		(thickness 1.6)
		(legacy_teardrops no)
	)
	(paper "A4")
	(title_block
		(title "Wiwynn_Tioga_Pass_MB.brd")
		(comment 1 "Tioga Pass / footprints 703-708 of 4770")
	)
	(layers
		(0 "F.Cu" signal "TOP")
		(4 "In1.Cu" signal "L2GND")
		(6 "In2.Cu" signal "L3")
		(8 "In3.Cu" signal "L4GND")
		(10 "In4.Cu" signal "L5")
		(12 "In5.Cu" signal "L6GND")
		(14 "In6.Cu" signal "L7VCC")
		(16 "In7.Cu" signal "L8VCC")
		(18 "In8.Cu" signal "L9GND")
		(20 "In9.Cu" signal "L10")
		(22 "In10.Cu" signal "L11GND")
		(24 "In11.Cu" signal "L12")
		(26 "In12.Cu" signal "L13GND")
		(2 "B.Cu" signal "BOTTOM")
		(9 "F.Adhes" user "F.Adhesive")
		(11 "B.Adhes" user "B.Adhesive")
		(13 "F.Paste" user "Package Geometry/Pastemask Top")
		(15 "B.Paste" user "Package Geometry/Pastemask Bottom")
		(5 "F.SilkS" user "Ref Des/Silkscreen Top")
		(7 "B.SilkS" user "Ref Des/Silkscreen Bottom")
		(1 "F.Mask" user "Board Geometry/Soldermask Top")
		(3 "B.Mask" user "Board Geometry/Soldermask Bottom")
		(17 "Dwgs.User" user "User.Drawings")
		(19 "Cmts.User" user "User.Comments")
		(21 "Eco1.User" user "User.Eco1")
		(23 "Eco2.User" user "User.Eco2")
		(25 "Edge.Cuts" user "Board Geometry/Outline")
		(27 "Margin" user)
		(31 "F.CrtYd" user "Package Geometry/Place Bound Top")
		(29 "B.CrtYd" user "Package Geometry/Place Bound Bottom")
		(35 "F.Fab" user "Ref Des/Assembly Top")
		(33 "B.Fab" user "Ref Des/Assembly Bottom")
	)
	(footprint ""
		(layer "F.Cu")
		(at 371.877844 -10.916158)
		(property "Reference" "C7G13"
			(at 0 0 0)
			(layer "F.SilkS")
			(hide yes)
			(effects
				(font
					(size 1.27 1.27)
				)
			)
		)
		(property "Value" ""
			(at 0 0 0)
			(layer "F.Fab")
			(effects
				(font
					(size 1.27 1.27)
				)
			)
		)
		(duplicate_pad_numbers_are_jumpers no)
		(fp_rect
			(start -0.3048 0.9906)
			(end 0.3048 -0.1016)
			(stroke
				(width 0)
				(type default)
			)
			(fill no)
			(layer "F.CrtYd")
		)
		(fp_line
			(start -0.3048 -0.1016)
			(end -0.3048 0.9906)
			(stroke
				(width 0.1)
				(type default)
			)
			(layer "F.Fab")
		)
		(fp_line
			(start -0.3048 0.9906)
			(end 0.3048 0.9906)
			(stroke
				(width 0.1)
				(type default)
			)
			(layer "F.Fab")
		)
		(fp_line
			(start 0.3048 -0.1016)
			(end -0.3048 -0.1016)
			(stroke
				(width 0.1)
				(type default)
			)
			(layer "F.Fab")
		)
		(fp_line
			(start 0.3048 0.9906)
			(end 0.3048 -0.1016)
			(stroke
				(width 0.1)
				(type default)
			)
			(layer "F.Fab")
		)
		(pad "1" smd rect
			(at 0 0)
			(size 0.508 0.508)
			(layers "F.Cu" "F.Mask" "F.Paste")
			(net "P3E_CPU0_PE2_SS_TXN<11>")
		)
		(pad "2" smd rect
			(at 0 0.889)
			(size 0.508 0.508)
			(layers "F.Cu" "F.Mask" "F.Paste")
			(net "P3E_CPU0_PE2_SS_C_TXN<11>")
		)
		(zone
			(layer "F.Cu")
			(hatch none 0.5)
			(connect_pads
				(clearance 0)
			)
			(min_thickness 0.25)
			(keepout
				(tracks allowed)
				(vias not_allowed)
				(pads allowed)
				(copperpour not_allowed)
				(footprints allowed)
			)
			(placement
				(enabled no)
				(sheetname "")
			)
			(fill
				(thermal_gap 0.5)
				(thermal_bridge_width 0.5)
				(island_removal_mode 0)
			)
			(polygon
				(pts
					(xy 371.623844 -10.281158) (xy 372.131844 -10.281158) (xy 372.131844 -10.662158) (xy 371.623844 -10.662158)
				)
			)
		)
		(zone
			(layer "F.Cu")
			(hatch none 0.5)
			(connect_pads
				(clearance 0)
			)
			(min_thickness 0.25)
			(keepout
				(tracks not_allowed)
				(vias allowed)
				(pads allowed)
				(copperpour not_allowed)
				(footprints allowed)
			)
			(placement
				(enabled no)
				(sheetname "")
			)
			(fill
				(thermal_gap 0.5)
				(thermal_bridge_width 0.5)
				(island_removal_mode 0)
			)
			(polygon
				(pts
					(xy 371.623844 -10.281158) (xy 372.131844 -10.281158) (xy 372.131844 -10.662158) (xy 371.623844 -10.662158)
				)
			)
		)
	)
	(footprint ""
		(layer "F.Cu")
		(at 29.213556 -31.141162 90)
		(property "Reference" "Q12W3"
			(at 0 0 90)
			(layer "F.SilkS")
			(hide yes)
			(effects
				(font
					(size 1.27 1.27)
				)
			)
		)
		(property "Value" "*"
			(at -4.572 -7.6835 90)
			(unlocked yes)
			(layer "F.Fab")
			(hide yes)
			(effects
				(font
					(size 1.27 1.016)
					(thickness 0.1524)
				)
			)
		)
		(property "Device Type" "BSL308C-H6327-GP_DISCRET-GB1-BA"
			(at -4.572 -9.2075 90)
			(unlocked yes)
			(layer "F.Fab")
			(hide yes)
			(effects
				(font
					(size 1.27 1.016)
					(thickness 0.1524)
				)
			)
		)
		(duplicate_pad_numbers_are_jumpers no)
		(fp_line
			(start 1.102868 -0.081534)
			(end 1.102868 0.081534)
			(stroke
				(width 0.1524)
				(type default)
			)
			(layer "F.SilkS")
		)
		(fp_line
			(start -1.8796 -0.081534)
			(end 1.102868 -0.081534)
			(stroke
				(width 0.1524)
				(type default)
			)
			(layer "F.SilkS")
		)
		(fp_line
			(start -1.8796 -0.081534)
			(end -1.524 0)
			(stroke
				(width 0.1524)
				(type default)
			)
			(layer "F.SilkS")
		)
		(fp_line
			(start -1.524 0)
			(end -1.8796 0.081534)
			(stroke
				(width 0.1524)
				(type default)
			)
			(layer "F.SilkS")
		)
		(fp_line
			(start 1.102868 0.081534)
			(end -1.8796 0.081534)
			(stroke
				(width 0.1524)
				(type default)
			)
			(layer "F.SilkS")
		)
		(fp_line
			(start -1.8796 0.081534)
			(end -1.8796 -0.081534)
			(stroke
				(width 0.1524)
				(type default)
			)
			(layer "F.SilkS")
		)
		(fp_line
			(start -1.7018 0.3048)
			(end -1.7018 1.8796)
			(stroke
				(width 0.508)
				(type default)
			)
			(layer "F.SilkS")
		)
		(fp_poly
			(pts
				(xy -1.179068 0.081534) (xy -1.179068 -0.081534) (xy 1.102868 -0.081534) (xy 1.102868 0.081534)
			)
			(stroke
				(width 0)
				(type default)
			)
			(fill yes)
			(layer "F.SilkS")
		)
		(fp_rect
			(start -1.4478 1.2446)
			(end 1.4478 -1.2446)
			(stroke
				(width 0)
				(type default)
			)
			(fill no)
			(layer "F.CrtYd")
		)
		(fp_poly
			(pts
				(xy -1.4478 -1.23952) (xy -1.9558 -1.23952) (xy -1.9558 2.1336) (xy 1.9558 2.1336) (xy 1.9558 -2.1336)
				(xy -1.9558 -2.1336) (xy -1.9558 -1.2446) (xy 1.4478 -1.2446) (xy 1.4478 1.2446) (xy -1.4478 1.2446)
			)
			(stroke
				(width 0)
				(type default)
			)
			(fill no)
			(layer "F.CrtYd")
		)
		(fp_rect
			(start -1.9558 2.1336)
			(end 1.9558 -2.1336)
			(stroke
				(width 0)
				(type default)
			)
			(fill no)
			(layer "F.Fab")
		)
		(pad "1" smd rect
			(at -0.950468 0.995934 90)
			(size 0.4572 1.27)
			(layers "F.Cu" "F.Mask" "F.Paste")
			(net "PWRGD_PVDDQ_GHJ")
		)
		(pad "2" smd rect
			(at 0 0.995934 90)
			(size 0.4572 1.27)
			(layers "F.Cu" "F.Mask" "F.Paste")
			(net "P12V_NVDIMM_GHJ")
		)
		(pad "3" smd rect
			(at 0.950468 0.995934 90)
			(size 0.4572 1.27)
			(layers "F.Cu" "F.Mask" "F.Paste")
			(net "PWRGD_PVDDQ_GHJ_N")
		)
		(pad "4" smd rect
			(at 0.950468 -0.995934 90)
			(size 0.4572 1.27)
			(layers "F.Cu" "F.Mask" "F.Paste")
			(net "P12V_NVDIMM_GHJ_D")
		)
		(pad "5" smd rect
			(at 0 -0.995934 90)
			(size 0.4572 1.27)
			(layers "F.Cu" "F.Mask" "F.Paste")
			(net "GND")
		)
		(pad "6" smd rect
			(at -0.950468 -0.995934 90)
			(size 0.4572 1.27)
			(layers "F.Cu" "F.Mask" "F.Paste")
			(net "PWRGD_PVDDQ_GHJ_N")
		)
	)
	(footprint ""
		(layer "F.Cu")
		(at 399.763996 -35.803586 -90)
		(property "Reference" "R8G4"
			(at 0 0 270)
			(layer "F.SilkS")
			(hide yes)
			(effects
				(font
					(size 1.27 1.27)
				)
			)
		)
		(property "Value" ""
			(at 0 0 270)
			(layer "F.Fab")
			(effects
				(font
					(size 1.27 1.27)
				)
			)
		)
		(duplicate_pad_numbers_are_jumpers no)
		(fp_poly
			(pts
				(xy -0.2794 -0.1016) (xy 0.2794 -0.1016) (xy 0.2794 0.9906) (xy -0.2794 0.9906)
			)
			(stroke
				(width 0)
				(type default)
			)
			(fill no)
			(layer "F.CrtYd")
		)
		(fp_line
			(start -0.2794 0.9906)
			(end 0.2794 0.9906)
			(stroke
				(width 0.1)
				(type default)
			)
			(layer "F.Fab")
		)
		(fp_line
			(start 0.2794 0.9906)
			(end 0.2794 -0.1016)
			(stroke
				(width 0.1)
				(type default)
			)
			(layer "F.Fab")
		)
		(fp_line
			(start -0.2794 -0.1016)
			(end -0.2794 0.9906)
			(stroke
				(width 0.1)
				(type default)
			)
			(layer "F.Fab")
		)
		(fp_line
			(start 0.2794 -0.1016)
			(end -0.2794 -0.1016)
			(stroke
				(width 0.1)
				(type default)
			)
			(layer "F.Fab")
		)
		(pad "1" smd rect
			(at 0 0 270)
			(size 0.508 0.508)
			(layers "F.Cu" "F.Mask" "F.Paste")
			(net "SMB_OCP_LAN_STBY_LVC3_SCL_R")
		)
		(pad "2" smd rect
			(at 0 0.889 270)
			(size 0.508 0.508)
			(layers "F.Cu" "F.Mask" "F.Paste")
			(net "SMB_OCP_LAN_STBY_LVC3_SCL")
		)
		(zone
			(layer "F.Cu")
			(hatch none 0.5)
			(connect_pads
				(clearance 0)
			)
			(min_thickness 0.25)
			(keepout
				(tracks not_allowed)
				(vias allowed)
				(pads allowed)
				(copperpour not_allowed)
				(footprints allowed)
			)
			(placement
				(enabled no)
				(sheetname "")
			)
			(fill
				(thermal_gap 0.5)
				(thermal_bridge_width 0.5)
				(island_removal_mode 0)
			)
			(polygon
				(pts
					(xy 399.128996 -36.057586) (xy 399.128996 -35.549586) (xy 399.509996 -35.549586) (xy 399.509996 -36.057586)
				)
			)
		)
		(zone
			(layer "F.Cu")
			(hatch none 0.5)
			(connect_pads
				(clearance 0)
			)
			(min_thickness 0.25)
			(keepout
				(tracks allowed)
				(vias not_allowed)
				(pads allowed)
				(copperpour not_allowed)
				(footprints allowed)
			)
			(placement
				(enabled no)
				(sheetname "")
			)
			(fill
				(thermal_gap 0.5)
				(thermal_bridge_width 0.5)
				(island_removal_mode 0)
			)
			(polygon
				(pts
					(xy 399.509996 -36.057586) (xy 399.509996 -35.549586) (xy 399.128996 -35.549586) (xy 399.128996 -36.057586)
				)
			)
		)
	)
	(footprint ""
		(layer "F.Cu")
		(at 418.6428 -86.4235)
		(property "Reference" "C8E2"
			(at 0 0 0)
			(layer "F.SilkS")
			(hide yes)
			(effects
				(font
					(size 1.27 1.27)
				)
			)
		)
		(property "Value" ""
			(at 0 0 0)
			(layer "F.Fab")
			(effects
				(font
					(size 1.27 1.27)
				)
			)
		)
		(duplicate_pad_numbers_are_jumpers no)
		(fp_poly
			(pts
				(xy 0.3048 -0.1016) (xy 0.3048 0.9906) (xy -0.3048 0.9906) (xy -0.3048 -0.1016)
			)
			(stroke
				(width 0)
				(type default)
			)
			(fill no)
			(layer "F.CrtYd")
		)
		(fp_line
			(start -0.3048 -0.1016)
			(end -0.3048 0.9906)
			(stroke
				(width 0.1)
				(type default)
			)
			(layer "F.Fab")
		)
		(fp_line
			(start -0.3048 0.9906)
			(end 0.3048 0.9906)
			(stroke
				(width 0.1)
				(type default)
			)
			(layer "F.Fab")
		)
		(fp_line
			(start 0.3048 -0.1016)
			(end -0.3048 -0.1016)
			(stroke
				(width 0.1)
				(type default)
			)
			(layer "F.Fab")
		)
		(fp_line
			(start 0.3048 0.9906)
			(end 0.3048 -0.1016)
			(stroke
				(width 0.1)
				(type default)
			)
			(layer "F.Fab")
		)
		(pad "1" smd rect
			(at 0 0)
			(size 0.508 0.508)
			(layers "F.Cu" "F.Mask" "F.Paste")
			(net "P3V3_STBY")
		)
		(pad "2" smd rect
			(at 0 0.889)
			(size 0.508 0.508)
			(layers "F.Cu" "F.Mask" "F.Paste")
			(net "GND")
		)
		(zone
			(layer "F.Cu")
			(hatch none 0.5)
			(connect_pads
				(clearance 0)
			)
			(min_thickness 0.25)
			(keepout
				(tracks allowed)
				(vias not_allowed)
				(pads allowed)
				(copperpour not_allowed)
				(footprints allowed)
			)
			(placement
				(enabled no)
				(sheetname "")
			)
			(fill
				(thermal_gap 0.5)
				(thermal_bridge_width 0.5)
				(island_removal_mode 0)
			)
			(polygon
				(pts
					(xy 418.3888 -86.1695) (xy 418.8968 -86.1695) (xy 418.8968 -85.7885) (xy 418.3888 -85.7885)
				)
			)
		)
		(zone
			(layer "F.Cu")
			(hatch none 0.5)
			(connect_pads
				(clearance 0)
			)
			(min_thickness 0.25)
			(keepout
				(tracks not_allowed)
				(vias allowed)
				(pads allowed)
				(copperpour not_allowed)
				(footprints allowed)
			)
			(placement
				(enabled no)
				(sheetname "")
			)
			(fill
				(thermal_gap 0.5)
				(thermal_bridge_width 0.5)
				(island_removal_mode 0)
			)
			(polygon
				(pts
					(xy 418.3888 -85.7885) (xy 418.8968 -85.7885) (xy 418.8968 -86.1695) (xy 418.3888 -86.1695)
				)
			)
		)
	)
	(footprint ""
		(layer "F.Cu")
		(at 450.1642 -147.7645 180)
		(property "Reference" "U25W11"
			(at 2.159 -1.57988 180)
			(unlocked yes)
			(layer "F.SilkS")
			(effects
				(font
					(size 0.4064 0.254)
					(thickness 0.1524)
				)
				(justify left)
			)
		)
		(property "Value" ""
			(at 0 0 180)
			(layer "F.Fab")
			(effects
				(font
					(size 1.27 1.27)
				)
			)
		)
		(duplicate_pad_numbers_are_jumpers no)
		(fp_line
			(start 4.4323 4.52628)
			(end 1.5367 4.52628)
			(stroke
				(width 0.1524)
				(type default)
			)
			(layer "F.SilkS")
		)
		(fp_line
			(start 4.4323 -0.64008)
			(end 4.4323 4.52628)
			(stroke
				(width 0.1524)
				(type default)
			)
			(layer "F.SilkS")
		)
		(fp_line
			(start 3.302 0.49022)
			(end 3.302 -0.64008)
			(stroke
				(width 0.1524)
				(type default)
			)
			(layer "F.SilkS")
		)
		(fp_line
			(start 2.667 0.49022)
			(end 3.302 0.49022)
			(stroke
				(width 0.1524)
				(type default)
			)
			(layer "F.SilkS")
		)
		(fp_line
			(start 2.667 -0.64008)
			(end 2.667 0.49022)
			(stroke
				(width 0.1524)
				(type default)
			)
			(layer "F.SilkS")
		)
		(fp_line
			(start 1.5367 4.52628)
			(end 1.5367 -0.64008)
			(stroke
				(width 0.1524)
				(type default)
			)
			(layer "F.SilkS")
		)
		(fp_line
			(start 1.5367 -0.64008)
			(end 4.4323 -0.64008)
			(stroke
				(width 0.1524)
				(type default)
			)
			(layer "F.SilkS")
		)
		(fp_circle
			(center -1.224788 -0.581152)
			(end -1.351788 -0.581152)
			(stroke
				(width 0.254)
				(type default)
			)
			(fill no)
			(layer "F.SilkS")
		)
		(fp_poly
			(pts
				(xy 0.7366 4.54152) (xy 0.7366 -0.64008) (xy 4.7244 -0.64008) (xy 5.2324 -0.64008) (xy 5.2324 4.54152)
				(xy 4.7244 4.54152)
			)
			(stroke
				(width 0)
				(type default)
			)
			(fill no)
			(layer "F.CrtYd")
		)
		(fp_line
			(start 5.2324 4.54152)
			(end 0.7366 4.54152)
			(stroke
				(width 0.1)
				(type default)
			)
			(layer "F.Fab")
		)
		(fp_line
			(start 5.2324 -0.64008)
			(end 5.2324 4.54152)
			(stroke
				(width 0.1)
				(type default)
			)
			(layer "F.Fab")
		)
		(fp_line
			(start 3.302 0.49022)
			(end 3.302 -0.64008)
			(stroke
				(width 0.1)
				(type default)
			)
			(layer "F.Fab")
		)
		(fp_line
			(start 2.667 0.49022)
			(end 3.302 0.49022)
			(stroke
				(width 0.1)
				(type default)
			)
			(layer "F.Fab")
		)
		(fp_line
			(start 2.667 -0.64008)
			(end 2.667 0.49022)
			(stroke
				(width 0.1)
				(type default)
			)
			(layer "F.Fab")
		)
		(fp_line
			(start 0.7366 4.54152)
			(end 0.7366 -0.64008)
			(stroke
				(width 0.1)
				(type default)
			)
			(layer "F.Fab")
		)
		(fp_line
			(start 0.7366 -0.64008)
			(end 5.2324 -0.64008)
			(stroke
				(width 0.1)
				(type default)
			)
			(layer "F.Fab")
		)
		(fp_circle
			(center -1.612138 -0.684784)
			(end -1.739138 -0.684784)
			(stroke
				(width 0.254)
				(type default)
			)
			(fill no)
			(layer "F.Fab")
		)
		(pad "1" smd rect
			(at 0 0 180)
			(size 2.159 0.381)
			(layers "F.Cu" "F.Mask" "F.Paste")
			(net "PD_GTL2014_DIR_6")
		)
		(pad "2" smd rect
			(at 0 0.65024 180)
			(size 2.159 0.381)
			(layers "F.Cu" "F.Mask" "F.Paste")
			(net "PD_GTL2014_6_B0")
		)
		(pad "3" smd rect
			(at 0 1.30048 180)
			(size 2.159 0.381)
			(layers "F.Cu" "F.Mask" "F.Paste")
			(net "XDP_PRDY_N")
		)
		(pad "4" smd rect
			(at 0 1.95072 180)
			(size 2.159 0.381)
			(layers "F.Cu" "F.Mask" "F.Paste")
			(net "P0V7_GTL2014_VREF_6")
		)
		(pad "5" smd rect
			(at 0 2.60096 180)
			(size 2.159 0.381)
			(layers "F.Cu" "F.Mask" "F.Paste")
			(net "PD_GTL2014_6_B2")
		)
		(pad "6" smd rect
			(at 0 3.2512 180)
			(size 2.159 0.381)
			(layers "F.Cu" "F.Mask" "F.Paste")
			(net "XDP_TDO")
		)
		(pad "7" smd rect
			(at 0 3.90144 180)
			(size 2.159 0.381)
			(layers "F.Cu" "F.Mask" "F.Paste")
			(net "GND")
		)
		(pad "8" smd rect
			(at 5.969 3.90144 180)
			(size 2.159 0.381)
			(layers "F.Cu" "F.Mask" "F.Paste")
			(net "GND")
		)
		(pad "9" smd rect
			(at 5.969 3.2512 180)
			(size 2.159 0.381)
			(layers "F.Cu" "F.Mask" "F.Paste")
			(net "JTAG_BMC_BUF_TDO_R")
		)
		(pad "10" smd rect
			(at 5.969 2.60096 180)
			(size 2.159 0.381)
			(layers "F.Cu" "F.Mask" "F.Paste")
			(net "TP_GTL2014_6_A2")
		)
		(pad "11" smd rect
			(at 5.969 1.95072 180)
			(size 2.159 0.381)
			(layers "F.Cu" "F.Mask" "F.Paste")
			(net "GND")
		)
		(pad "12" smd rect
			(at 5.969 1.30048 180)
			(size 2.159 0.381)
			(layers "F.Cu" "F.Mask" "F.Paste")
			(net "BMC_PRDY_N")
		)
		(pad "13" smd rect
			(at 5.969 0.65024 180)
			(size 2.159 0.381)
			(layers "F.Cu" "F.Mask" "F.Paste")
			(net "TP_GTL2014_6_A0")
		)
		(pad "14" smd rect
			(at 5.969 0 180)
			(size 2.159 0.381)
			(layers "F.Cu" "F.Mask" "F.Paste")
			(net "P3V3_STBY")
		)
	)
	(footprint ""
		(layer "F.Cu")
		(at 490.2581 -46.7614 90)
		(property "Reference" "R9E8"
			(at 0 0 90)
			(layer "F.SilkS")
			(hide yes)
			(effects
				(font
					(size 1.27 1.27)
				)
			)
		)
		(property "Value" ""
			(at 0 0 90)
			(layer "F.Fab")
			(effects
				(font
					(size 1.27 1.27)
				)
			)
		)
		(duplicate_pad_numbers_are_jumpers no)
		(fp_poly
			(pts
				(xy -0.2794 -0.1016) (xy 0.2794 -0.1016) (xy 0.2794 0.9906) (xy -0.2794 0.9906)
			)
			(stroke
				(width 0)
				(type default)
			)
			(fill no)
			(layer "F.CrtYd")
		)
		(fp_line
			(start 0.2794 -0.1016)
			(end -0.2794 -0.1016)
			(stroke
				(width 0.1)
				(type default)
			)
			(layer "F.Fab")
		)
		(fp_line
			(start -0.2794 -0.1016)
			(end -0.2794 0.9906)
			(stroke
				(width 0.1)
				(type default)
			)
			(layer "F.Fab")
		)
		(fp_line
			(start 0.2794 0.9906)
			(end 0.2794 -0.1016)
			(stroke
				(width 0.1)
				(type default)
			)
			(layer "F.Fab")
		)
		(fp_line
			(start -0.2794 0.9906)
			(end 0.2794 0.9906)
			(stroke
				(width 0.1)
				(type default)
			)
			(layer "F.Fab")
		)
		(pad "1" smd rect
			(at 0 0 90)
			(size 0.508 0.508)
			(layers "F.Cu" "F.Mask" "F.Paste")
			(net "SPI_NIC_SCLK_R")
		)
		(pad "2" smd rect
			(at 0 0.889 90)
			(size 0.508 0.508)
			(layers "F.Cu" "F.Mask" "F.Paste")
			(net "SPI_NIC_SCLK")
		)
		(zone
			(layer "F.Cu")
			(hatch none 0.5)
			(connect_pads
				(clearance 0)
			)
			(min_thickness 0.25)
			(keepout
				(tracks allowed)
				(vias not_allowed)
				(pads allowed)
				(copperpour not_allowed)
				(footprints allowed)
			)
			(placement
				(enabled no)
				(sheetname "")
			)
			(fill
				(thermal_gap 0.5)
				(thermal_bridge_width 0.5)
				(island_removal_mode 0)
			)
			(polygon
				(pts
					(xy 490.5121 -46.5074) (xy 490.5121 -47.0154) (xy 490.8931 -47.0154) (xy 490.8931 -46.5074)
				)
			)
		)
		(zone
			(layer "F.Cu")
			(hatch none 0.5)
			(connect_pads
				(clearance 0)
			)
			(min_thickness 0.25)
			(keepout
				(tracks not_allowed)
				(vias allowed)
				(pads allowed)
				(copperpour not_allowed)
				(footprints allowed)
			)
			(placement
				(enabled no)
				(sheetname "")
			)
			(fill
				(thermal_gap 0.5)
				(thermal_bridge_width 0.5)
				(island_removal_mode 0)
			)
			(polygon
				(pts
					(xy 490.8931 -46.5074) (xy 490.8931 -47.0154) (xy 490.5121 -47.0154) (xy 490.5121 -46.5074)
				)
			)
		)
	)
)
